FILE_TYPE = CONNECTIVITY;
{Allegro Design Entry HDL 16.6-p007 (v16-6-112F) 10/10/2012}
"PAGE_NUMBER" = 204;
0"NC";
1"GND\g";
2"PVCCIN_CPU0\g";
3"VR_FET_SW_P12V_STBY_PVCCIN_CPU0\g";
4"GND\g";
5"VR_FET_SW_P12V_STBY_PVCCIN_CPU0\g";
6"GND\g";
7"GND\g";
8"GND\g";
9"PVCCIN_CPU0\g";
10"GND\g";
11"P12V_STBY\g";
12"P5V_STBY\g";
13"GND\g";
14"GND\g";
15"GND\g";
16"GND\g";
17"GND\g";
18"NC_PVCCIN_CPU0_PH5_P31";
19"A_TSENSE_PVCCIN_CPU0";
20"VR_PVCCIN_CPU0_PH5_PHASE"VOLTAGE"5";
21"VR_PVCCIN_CPU0_PWM5";
22"TP_PVCCIN_CPU0_PH5_GL_0";
23"TP_PVCCIN_CPU0_PH5_GL_1";
24"VR_FET_SW_P12V_PVCCIN_CPU0_R";
25"UN$204$3D01R5F-GP$I91$2";
26"VR_PVCCIN_CPU0_AIREF5";
27"VR_PVCCIN_CPU0_PH5_BOOT_R";
28"VR_PVCCIN_CPU0_PH5_BOOT";
29"VR_PVCCIN_CPU0_PHASE5"VOLTAGE"5";
30"ISENSE_PVCCIN_CPU0_PH5_IMON";
31"VR_PVCCIN_CPU0_PH5_OCSET"VOLTAGE"3.6";
32"PVCCIN_PVSA_CPU0_IINSEN";
33"VR_PVCCIN_CPU0_PH5_VCIN"VOLTAGE"5";
34"VSENSE_PVCCIN_CPU0_P";
35"VSENSE_PVCCIN_CPU0_SKT_VRTN";
36"VSENSE_PVCCIN_CPU0_SKT_VSEN";
37"VSENSE_PVCCIN_CPU0_N";
%"GND"
"1","(-2850,3050)","0","mstr_symbols","I13";
;
ROOM"PVCCIN_CPU0_PWR_VR"
BOM_COST"PROC_VRD_VCCIN_CPU0"
BODY_TYPE"PLUMBING"
SIZE"1B"
CDS_LIB"mstr_symbols"
VOLTAGE"0"
HDL_POWER"GND";
"A\NAC"1;
%"CAP"
"1","(-5675,3975)","0","mstr_discrete","I18";
;
CDS_SEC"1"
CDS_LOCATION"C4D47"
CDS_LIB"mstr_discrete"
SEC_TYPE"0402"
ROOM"PVCCIN_CPU0_PWR_VR"
SEC"1"
PART_NUMBER"A36096-155"
MATERIAL"X7R"
LOCATION"C4D47"
PACK_TYPE"0402"
TOLERANCE"10%"
VALUE"0.22UF"
VOLTAGE"16V";
"A"
$PN"1"12;
"B"
$PN"2"4;
%"CAP_A"
"1","(-5825,3975)","2","dev_discrete","I19";
;
CDS_LIB"dev_discrete"
CDS_LOCATION"C4C14"
CDS_SEC"1"
SEC_TYPE"0402V"
SEC"1"
ROOM"PVCCIN_CPU0_PWR_VR"
LOCATION"C4C14"
MATERIAL"X6S"
VOLTAGE"6.3V"
TOLERANCE"10%"
VALUE"1.0UF"
PACK_TYPE"0402V"
PART_NUMBER"D97712-004";
"B"
$PN"2"4;
"A"
$PN"1"12;
%"CAP"
"1","(-6200,3350)","2","mstr_discrete","I22";
;
CDS_SEC"1"
NO_XNET_CONNECTION"1"
SEC_TYPE"0402"
SPOF"TRUE"
CDS_LIB"mstr_discrete"
SEC"1"
CDS_LOCATION"C4C17"
ROOM"PVCCIN_CPU0_PWR_VR"
PACK_TYPE"0402"
LOCATION"C4C17"
VALUE"0.220UF"
VOLTAGE"16V"
TOLERANCE"10%"
MATERIAL"X7R"
PART_NUMBER"A36096-104";
"A"
$PN"1"28;
"B"
$PN"2"20;
%"RES"
"1","(-6100,4525)","0","mstr_discrete","I33";
;
CDS_SEC"1"
CDS_LOCATION"R6P47"
SEC_TYPE"0402"
SEC"1"
ROOM"PVCCIN_CPU0_PWR_VR"
CDS_LIB"mstr_discrete"
MATERIAL"CHIP"
PACK_TYPE"0402"
WATTAGE"1/16W"
TOLERANCE"1%"
PART_NUMBER"G21796-090"
LOCATION"R6P47"
VALUE"1.0";
"B"
$PN"2"12;
"A"
$PN"1"33;
%"CAP"
"1","(-6425,3950)","0","mstr_discrete","I34";
;
CDS_SEC"1"
CDS_LOCATION"C4D46"
CDS_LIB"mstr_discrete"
ROOM"PVCCIN_CPU0_PWR_VR"
SEC"1"
SEC_TYPE"0402"
PART_NUMBER"D97712-011"
MATERIAL"X6S"
VOLTAGE"16V"
PACK_TYPE"0402"
TOLERANCE"10%"
VALUE"1.0UF"
LOCATION"C4D46";
"A"
$PN"1"33;
"B"
$PN"2"4;
%"CAP_A"
"1","(-6650,3975)","0","dev_discrete","I35";
;
CDS_LOCATION"C4C19"
CDS_LIB"dev_discrete"
SEC"1"
SEC_TYPE"0402V"
CDS_SEC"1"
ROOM"PVCCIN_CPU0_PWR_VR"
LOCATION"C4C19"
PART_NUMBER"A36096-030"
VALUE"0.1UF"
TOLERANCE"10%"
MATERIAL"X7R"
VOLTAGE"16V"
PACK_TYPE"0402V";
"B"
$PN"2"4;
"A"
$PN"1"3;
%"CAP"
"1","(-6875,3925)","0","mstr_discrete","I36";
;
CDS_SEC"1"
CDS_LOCATION"C4C18"
CDS_LIB"mstr_discrete"
ROOM"PVCCIN_CPU0_PWR_VR"
SEC"1"
SEC_TYPE"0402"
PART_NUMBER"D97712-011"
VOLTAGE"16V"
TOLERANCE"10%"
VALUE"1.0UF"
LOCATION"C4C18"
MATERIAL"X6S"
PACK_TYPE"0402";
"A"
$PN"1"3;
"B"
$PN"2"4;
%"CAP"
"1","(-7100,3975)","0","mstr_discrete","I37";
;
CDS_SEC"1"
CDS_LOCATION"C6N10"
CDS_LIB"mstr_discrete"
ROOM"PVCCIN_CPU0_PWR_VR"
SEC"1"
SEC_TYPE"0805"
LOCATION"C6N10"
PART_NUMBER"C95333-007"
MATERIAL"X6S"
VOLTAGE"16V"
TOLERANCE"10%"
VALUE"10UF"
PACK_TYPE"0805";
"A"
$PN"1"3;
"B"
$PN"2"4;
%"CAP"
"1","(-7325,3925)","0","mstr_discrete","I38";
;
CDS_SEC"1"
CDS_LIB"mstr_discrete"
CDS_LOCATION"C6P17"
ROOM"PVCCIN_CPU0_PWR_VR"
SEC_TYPE"0805"
SEC"1"
VALUE"10UF"
LOCATION"C6P17"
VOLTAGE"16V"
TOLERANCE"10%"
MATERIAL"X6S"
PART_NUMBER"C95333-007"
PACK_TYPE"0805";
"A"
$PN"1"3;
"B"
$PN"2"4;
%"PVCCIN_CPU0"
"1","(-775,3500)","0","mstr_symbols","I4";
;
BODY_TYPE"PLUMBING"
VOLTAGE"2.0V"
CDS_LIB"mstr_symbols"
HDL_POWER"PVCCIN_CPU0";
"G\NAC"2;
%"VCC_CORE"
"1","(-7550,4300)","0","mstr_symbols","I41";
;
CDS_LIB"mstr_symbols"
HDL_POWER"VR_FET_SW_P12V_STBY_PVCCIN_CPU0";
"A"3;
%"CAP"
"1","(-7550,3950)","0","mstr_discrete","I42";
;
CDS_SEC"1"
CDS_LOCATION"C6N11"
CDS_LIB"mstr_discrete"
ROOM"PVCCIN_CPU0_PWR_VR"
SEC"1"
SEC_TYPE"0805"
MATERIAL"X6S"
VOLTAGE"16V"
PACK_TYPE"0805"
TOLERANCE"10%"
VALUE"10UF"
LOCATION"C6N11"
PART_NUMBER"C95333-007";
"A"
$PN"1"3;
"B"
$PN"2"4;
%"GND"
"1","(-7550,3550)","0","mstr_symbols","I43";
;
ROOM"PVCCIN_CPU0_PWR_VR"
BOM_COST"PROC_VRD_VCCIN_CPU0"
BODY_TYPE"PLUMBING"
SIZE"1B"
CDS_LIB"mstr_symbols"
VOLTAGE"0"
HDL_POWER"GND";
"A\NAC"4;
%"VCC_CORE"
"1","(-575,2450)","0","mstr_symbols","I44";
;
CDS_LIB"mstr_symbols"
HDL_POWER"VR_FET_SW_P12V_STBY_PVCCIN_CPU0";
"A"5;
%"RES"
"1","(-1825,2175)","0","mstr_discrete","I45";
;
CDS_SEC"1"
CDS_LIB"mstr_discrete"
CDS_LOCATION"R4C6"
ROOM"PVCCIN_CPU0_FILTER_VR"
SEC_TYPE"2010"
SEC"1"
TOLERANCE"1%"
LOCATION"R4C6"
PART_NUMBER"E30969-002"
VALUE"0.001"
WATTAGE"1W"
MATERIAL"CHIP"
PACK_TYPE"2010";
"B"
$PN"2"5;
"A"
$PN"1"24;
%"INDUCTOR"
"1","(-2975,2175)","0","mstr_discrete","I46";
;
CDS_SEC"1"
CDS_LOCATION"L4C1"
ROOM"PVCCIN_CPU0_FILTER_VR"
SEC_TYPE"SM"
SEC"1"
CDS_LIB"mstr_discrete"
PART_NUMBER"D92183-019"
LOCATION"L4C1"
MATERIAL"IND"
PACK_TYPE"SM"
VALUE"100NH";
"INA\NAC"
$PN"1"11;
"INB\NAC"
$PN"2"24;
%"CAPP"
"1","(-925,1975)","0","mstr_discrete","I48";
;
CDS_SEC"1"
CDS_LIB"mstr_discrete"
ROOM"PVCCIN_CPU0_FILTER_VR"
CDS_LOCATION"C4D2"
SEC"1"
SEC_TYPE"2626"
LOCATION"C4D2"
VALUE"270UF"
MATERIAL"OSCON"
PACK_TYPE"2626"
PART_NUMBER"A31228-047"
VOLTAGE"16V"
TOLERANCE"20%";
"B"
$PN"2"6;
"A"
$PN"1"5;
%"GND"
"1","(-1175,1575)","0","mstr_symbols","I49";
;
ROOM"PVCCIN_CPU0_FILTER_VR"
BOM_COST"PROC_VRD_VCCIN_CPU0"
BODY_TYPE"PLUMBING"
SIZE"1B"
VOLTAGE"0"
CDS_LIB"mstr_symbols"
HDL_POWER"GND";
"A\NAC"6;
%"INDUCTOR"
"1","(-1925,3400)","0","mstr_discrete","I5";
;
CDS_LIB"mstr_discrete"
CDS_LOCATION"L4C3"
ROOM"PVCCIN_CPU0_PWR_VR"
$SEC"1"
CDS_SEC"1"
MATERIAL"IND"
LOCATION"L4C3"
VALUE"0.12UH"
PACK_TYPE"SM"
PART_NUMBER"D92183-034";
"INA\NAC"
$PN"1"29;
"INB\NAC"
$PN"2"2;
%"CAPP"
"1","(-1400,2000)","0","mstr_discrete","I50";
;
CDS_SEC"1"
CDS_LIB"mstr_discrete"
SEC_TYPE"2626"
SEC"1"
CDS_LOCATION"C4E16"
ROOM"PVCCIN_CPU0_FILTER_VR"
LOCATION"C4E16"
VALUE"270UF"
MATERIAL"OSCON"
VOLTAGE"16V"
PACK_TYPE"2626"
TOLERANCE"20%"
PART_NUMBER"A31228-047";
"B"
$PN"2"6;
"A"
$PN"1"5;
%"CAP_A"
"1","(-2225,1050)","0","dev_discrete","I51";
;
$SEC"1"
CDS_LIB"dev_discrete"
CDS_LOCATION"C4C2"
ROOM"PVCCIN_CPU0_FILTER_VR"
CDS_SEC"1"
PACK_TYPE"0402V"
VALUE"0.1UF"
PART_NUMBER"A36096-030"
MATERIAL"EMPTY"
VOLTAGE"16V"
LOCATION"C4C2"
TOLERANCE"10%";
"B"
$PN"2"7;
"A"
$PN"1"24;
%"GND"
"1","(-2225,800)","0","mstr_symbols","I52";
;
ROOM"PVCCIN_CPU0_FILTER_VR"
BOM_COST"PROC_VRD_VCCIN_CPU0"
BODY_TYPE"PLUMBING"
SIZE"1B"
CDS_LIB"mstr_symbols"
VOLTAGE"0"
HDL_POWER"GND";
"A\NAC"7;
%"ADM4073"
"1","(-2750,1275)","2","mstr_analog","I53";
;
CDS_SEC"1"
CDS_LIB"mstr_analog"
ROOM"PVCCIN_CPU0_FILTER_VR"
CDS_LOCATION"U4C1"
SEC"1"
SEC_TYPE"SM"
PACK_TYPE"SM"
LOCATION"U4C1"
MATERIAL"EMPTY"
PART_NUMBER"G12194-001";
"GND<0>"
$PN"1"8;
"GND<1>"
$PN"2"8;
"OUT"
$PN"6"32;
"RSN"
$PN"5"5;
"RSP"
$PN"4"24;
"VCC"
$PN"3"24;
%"GND"
"1","(-3275,950)","0","mstr_symbols","I54";
;
BODY_TYPE"PLUMBING"
CDS_LIB"mstr_symbols"
SIZE"1B"
VOLTAGE"0"
ROOM"PVCCIN_CPU0_FILTER_VR"
BOM_COST"PROC_VRD_VCCIN_CPU0"
HDL_POWER"GND";
"A\NAC"8;
%"PVCCIN_CPU0"
"1","(-4625,2375)","0","mstr_symbols","I58";
;
HDL_POWER"PVCCIN_CPU0"
VOLTAGE"2.0V"
CDS_LIB"mstr_symbols"
BODY_TYPE"PLUMBING";
"G\NAC"9;
%"GND"
"1","(-4800,700)","0","mstr_symbols","I59";
;
ROOM"PVCCIN_CPU0_VSENSE_VR"
BOM_COST"PROC_VRD_VCCIN_CPU0"
BODY_TYPE"PLUMBING"
CDS_LIB"mstr_symbols"
SIZE"1B"
VOLTAGE"0"
HDL_POWER"GND";
"A\NAC"10;
%"RES"
"1","(-5475,2225)","0","mstr_discrete","I60";
;
CDS_LOCATION"R4E14"
CDS_LIB"mstr_discrete"
MATERIAL"CHIP"
BOM_COST"PROC_VRD_VCCIN_CPU0"
ROOM"PVCCIN_CPU0_VSENSE_VR"
$SEC"1"
CDS_SEC"1"
PART_NUMBER"G21796-017"
TOLERANCE"1%"
WATTAGE"1/16W"
VALUE"100.0"
LOCATION"R4E14"
PACK_TYPE"0402";
"B"
$PN"2"9;
"A"
$PN"1"34;
%"RES"
"1","(-5475,1825)","0","mstr_discrete","I61";
;
ROOM"PVCCIN_CPU0_VSENSE_VR"
CDS_LOCATION"R4E16"
BOM_COST"PROC_VRD_VCCIN_CPU0"
CDS_LIB"mstr_discrete"
$SEC"1"
CDS_SEC"1"
NO_XNET_CONNECTION"1"
MATERIAL"CHIP"
PART_NUMBER"G21497-005"
LOCATION"R4E16"
PACK_TYPE"0402"
VALUE"0.0"
TOLERANCE"5%"
WATTAGE"1/16W";
"B"
$PN"2"36;
"A"
$PN"1"34;
%"RES"
"1","(-5450,1375)","0","mstr_discrete","I62";
;
CDS_LIB"mstr_discrete"
CDS_LOCATION"R4E17"
ROOM"PVCCIN_CPU0_VSENSE_VR"
BOM_COST"PROC_VRD_VCCIN_CPU0"
$SEC"1"
CDS_SEC"1"
NO_XNET_CONNECTION"1"
MATERIAL"CHIP"
PART_NUMBER"G21497-005"
LOCATION"R4E17"
TOLERANCE"5%"
VALUE"0.0"
WATTAGE"1/16W"
PACK_TYPE"0402";
"B"
$PN"2"35;
"A"
$PN"1"37;
%"RES"
"2","(-6275,1625)","0","mstr_discrete","I63";
;
CDS_LIB"mstr_discrete"
CDS_LOCATION"R4E15"
ROOM"PVCCIN_CPU0_VSENSE_VR"
$SEC"1"
CDS_SEC"1"
BOM_COST"PROC_VRD_VCCIN_CPU0"
WATTAGE"1/16W"
PACK_TYPE"0402"
VALUE"1.00K"
PART_NUMBER"G21796-026"
LOCATION"R4E15"
MATERIAL"EMPTY"
NO_XNET_CONNECTION"1"
TOLERANCE"1%";
"A"
$PN"1"34;
"B"
$PN"2"37;
%"RES"
"1","(-5450,975)","0","mstr_discrete","I64";
;
MATERIAL"CHIP"
CDS_LIB"mstr_discrete"
BOM_COST"PROC_VRD_VCCIN_CPU0"
ROOM"PVCCIN_CPU0_VSENSE_VR"
CDS_LOCATION"R4E18"
$SEC"1"
CDS_SEC"1"
PART_NUMBER"G21796-017"
LOCATION"R4E18"
TOLERANCE"1%"
PACK_TYPE"0402"
VALUE"100.0"
WATTAGE"1/16W";
"B"
$PN"2"10;
"A"
$PN"1"37;
%"CAPP"
"1","(-575,1975)","0","mstr_discrete","I67";
;
CDS_SEC"1"
CDS_LIB"mstr_discrete"
CDS_LOCATION"C4C12"
ROOM"PVCCIN_CPU0_FILTER_VR"
SEC"1"
SEC_TYPE"2626"
LOCATION"C4C12"
VALUE"270UF"
MATERIAL"OSCON"
VOLTAGE"16V"
PACK_TYPE"2626"
TOLERANCE"20%"
PART_NUMBER"A31228-047";
"B"
$PN"2"6;
"A"
$PN"1"5;
%"P12V_STBY"
"1","(-3325,2425)","0","mstr_symbols","I68";
;
HDL_POWER"P12V_STBY"
VOLTAGE"12.0V"
BODY_TYPE"PLUMBING"
SIZE"1B"
CDS_LIB"mstr_symbols";
"G\NAC"11;
%"P5V_STBY"
"1","(-5325,4650)","0","mstr_symbols","I69";
;
HDL_POWER"P5V_STBY"
VOLTAGE"5.0V"
BODY_TYPE"PLUMBING"
SIZE"1B"
CDS_LIB"mstr_symbols";
"G\NAC"12;
%"CAP_A"
"1","(-775,3000)","0","dev_discrete","I70";
;
CDS_LIB"dev_discrete"
CDS_LOCATION"C6R2"
CDS_SEC"1"
SEC_TYPE"0603V"
SEC"1"
LOCATION"C6R2"
VALUE"22.0UF"
PART_NUMBER"E15431-004"
MATERIAL"X6S"
VOLTAGE"4V"
PACK_TYPE"0603V"
TOLERANCE"20%";
"B"
$PN"2"13;
"A"
$PN"1"2;
%"IR354XX"
"1","(-3500,3700)","0","mstr_discrete","I71";
;
CDS_LIB"mstr_discrete"
PACK_TYPE"SM"
CDS_SEC"1"
$SEC"1"
CDS_LOCATION"EU4C2"
VALUE"IR35411"
LOCATION"EU4C2"
MATERIAL"IC"
PART_NUMBER"H73688-001";
"TOUT_FLT"
$PN"36"19;
"NC"
$PN"31"18;
"OCSET"
$PN"37"31;
"IOUT"
$PN"38"30;
"SW"
$PN"10"29;
"BOOST"
$PN"33"27;
"REFIN"
$PN"39"26;
"PWM"
$PN"34"21;
"PHASE"
$PN"32"20;
"VIN<0>"
$PN"25"3;
"VCC"
$PN"3"33;
"VIN<1>"
$PN"30"3;
"EN"
$PN"35"12;
"VDRV"
$PN"4"12;
"VOS"
$PN"1"2;
"LGND"
$PN"2"1;
"PGND<1>"
$PN"7"1;
"PGND<2>"
$PN"40"1;
"PGND<0>"
$PN"5"1;
"GL<0>"
$PN"6"22;
"GL<1>"
$PN"41"23;
%"GND"
"1","(-775,2675)","0","mstr_symbols","I8";
;
HDL_POWER"GND"
CDS_LIB"mstr_symbols"
SIZE"1B"
VOLTAGE"0"
BODY_TYPE"PLUMBING"
BOM_COST"PROC_VRD_VCCIN_CPU0"
ROOM"PVCCIN_CPU0_PWR_VR";
"A\NAC"13;
%"RES"
"2","(-775,3850)","0","mstr_discrete","I83";
;
CDS_SEC"1"
CDS_LOCATION"R4D68"
CDS_LIB"mstr_discrete"
SEC"1"
SEC_TYPE"0402"
PART_NUMBER"G21796-187"
VALUE"68.1K"
LOCATION"R4D68"
TOLERANCE"1%"
WATTAGE"1/16W"
PACK_TYPE"0402"
MATERIAL"EMPTY";
"A"
$PN"1"31;
"B"
$PN"2"14;
%"GND"
"1","(-775,3625)","0","mstr_symbols","I84";
;
ROOM"PVCCIN_CPU0_PWR_VR"
BOM_COST"PROC_VRD_VCCIN_CPU0"
BODY_TYPE"PLUMBING"
SIZE"1B"
CDS_LIB"mstr_symbols"
VOLTAGE"0"
HDL_POWER"GND";
"A\NAC"14;
%"CAP_A"
"1","(-4225,3200)","0","dev_discrete","I85";
;
CDS_SEC"1"
$SEC"1"
CDS_LOCATION"CT36"
ROOM"PVCCIN_CPU0_PWR_VR"
CDS_LIB"dev_discrete"
VALUE"0.1UF"
PART_NUMBER"A36096-030"
PACK_TYPE"0402V"
MATERIAL"X7R"
TOLERANCE"10%"
VOLTAGE"16V"
STATUS"NOPOP"
LOCATION"CT36";
"B"
$PN"2"15;
"A"
$PN"1"26;
%"GND"
"1","(-4225,2950)","0","mstr_symbols","I86";
;
BODY_TYPE"PLUMBING"
ROOM"PVCCIN_CPU0_PWR_VR"
BOM_COST"PROC_VRD_VCCIN_CPU0"
SIZE"1B"
VOLTAGE"0"
HDL_POWER"GND"
CDS_LIB"mstr_symbols";
"A\NAC"15;
%"CAP"
"1","(-2450,3725)","0","mstr_discrete","I88";
;
CDS_SEC"1"
$SEC"1"
CDS_LOCATION"CT34"
ROOM"VDDQ_KLM_PWR_VR"
CDS_LIB"mstr_discrete"
LOCATION"CT34"
MATERIAL"X7R"
VOLTAGE"50V"
PACK_TYPE"0402LF"
VALUE"1000PF"
PART_NUMBER"A36096-046"
TOLERANCE"10%"
STATUS"NOPOP";
"A"
$PN"1"19;
"B"
$PN"2"16;
%"GND"
"1","(-2450,3525)","0","mstr_symbols","I89";
;
HDL_POWER"GND"
SIZE"1B"
BODY_TYPE"PLUMBING"
VOLTAGE"0"
ROOM"VDDQ_KLM_PWR_VR"
CDS_LIB"mstr_symbols";
"A\NAC"16;
%"CAP_A"
"1","(-1100,3100)","0","dev_discrete","I9";
;
CDS_LOCATION"C4D12"
BOM_COST"PROC_VRD_VCCIN_CPU0"
CDS_LIB"dev_discrete"
CDS_SEC"1"
ROOM"PVCCIN_CPU0_PWR_VR"
SEC_TYPE"0603V"
SEC"1"
MATERIAL"X6S"
VOLTAGE"4V"
PACK_TYPE"0603V"
PART_NUMBER"E15431-004"
TOLERANCE"20%"
VALUE"22.0UF"
LOCATION"C4D12";
"B"
$PN"2"13;
"A"
$PN"1"2;
%"SC2K2P50V3KX-GP"
"1","(-2350,3275)","0","w_hdl","I90";
;
CDS_SEC"1"
$SEC"1"
CDS_LOCATION"CT35"
CDS_LIB"w_hdl"
CDS_LMAN_SYM_OUTLINE"-50,25,50,-25"
PACK_TYPE"SMD-BCG6"
PART_NUMBER"78.22224.2BL"
LOCATION"CT35"
VALUE"SC2K2P50V3KX-GP"
STATUS"NOPOP";
"2"
$PN"2"25;
"1"
$PN"1"29;
%"3D01R5F-GP"
"1","(-2350,2975)","4","w_hdl","I91";
;
CDS_SEC"1"
$SEC"1"
CDS_LOCATION"RT24"
CDS_LMAN_SYM_OUTLINE"-50,75,50,-75"
CDS_LIB"w_hdl"
PART_NUMBER"64.3R015.16L"
PACK_TYPE"SMD-RG5"
LOCATION"RT24"
VALUE"3D01R5F-GP"
STATUS"NOPOP";
"2"
$PN"2"25;
"1"
$PN"1"17;
%"GND"
"1","(-2350,2750)","0","mstr_symbols","I92";
;
ROOM"PVCCIN_CPU0_PWR_VR"
BOM_COST"PROC_VRD_VCCIN_CPU0"
BODY_TYPE"PLUMBING"
VOLTAGE"0"
SIZE"1B"
HDL_POWER"GND"
CDS_LIB"mstr_symbols";
"A\NAC"17;
%"RES"
"1","(-5275,3500)","0","mstr_discrete","I93";
;
CDS_SEC"1"
$SEC"1"
CDS_LOCATION"RT23"
CDS_LIB"mstr_discrete"
BOM_COST"DEBUG"
ROOM"BMC_DEBUG_HEADER"
LOCATION"RT23"
WATTAGE"1/16W"
VALUE"0.0"
PART_NUMBER"G21497-005"
TOLERANCE"5%"
MATERIAL"CHIP"
PACK_TYPE"0402";
"B"
$PN"2"27;
"A"
$PN"1"28;
END.
